# S9S_MB_2U (Grand Teton) — schematic netlist excerpt (pin names and nets, part order shuffled) for the footprints in the layout excerpt that follows; sources: Cadence DE-HDL packaged netlist, KiCad conversion of 03242023_DA0F0TMBIJ0_F0T_Motherboard_J_brd_V01_OCP.brd

R30  Q_RES  54.9K 1% CHIP  pkg 0402LF  page 86 : A = PD_CHC_CPU0_DIMM1_SAA ; B = GND
PR288  Q_RES  2.2 1% CHIP  pkg 0402LF  page 288 : A = PVCCIN_CPU1_PVCC ; B = PVCCIN_CPU1_VDD7
PC303_P0_1  Q_CAP  22UF 16V 20% X6S  pkg C0805  page 267 : A = SW_P12V_PVCCIN_CPU0_FLT ; B = GND

(kicad_pcb
	(version 20260206)
	(generator "pcbnew")
	(generator_version "10.0")
	(general
		(thickness 1.6)
		(legacy_teardrops no)
	)
	(paper "A4")
	(title_block
		(title "03242023_DA0F0TMBIJ0_F0T_Motherboard_J_brd_V01_OCP.brd")
		(comment 1 "Grand Teton / footprints 4838-4840 of 6105")
	)
	(layers
		(0 "F.Cu" signal "TOP")
		(4 "In1.Cu" signal "GND")
		(6 "In2.Cu" signal "IN1")
		(8 "In3.Cu" signal "GND1")
		(10 "In4.Cu" signal "IN2")
		(12 "In5.Cu" signal "GND2")
		(14 "In6.Cu" signal "IN3")
		(16 "In7.Cu" signal "GND3")
		(18 "In8.Cu" signal "VCC")
		(20 "In9.Cu" signal "VCC1")
		(22 "In10.Cu" signal "GND4")
		(24 "In11.Cu" signal "IN4")
		(26 "In12.Cu" signal "GND5")
		(28 "In13.Cu" signal "IN5")
		(30 "In14.Cu" signal "GND6")
		(32 "In15.Cu" signal "IN6")
		(34 "In16.Cu" signal "GND7")
		(2 "B.Cu" signal "BOTTOM")
		(9 "F.Adhes" user "F.Adhesive")
		(11 "B.Adhes" user "B.Adhesive")
		(13 "F.Paste" user "Package Geometry/Pastemask Top")
		(15 "B.Paste" user "Package Geometry/Pastemask Bottom")
		(5 "F.SilkS" user "Ref Des/Silkscreen Top")
		(7 "B.SilkS" user "Ref Des/Silkscreen Bottom")
		(1 "F.Mask" user "Board Geometry/Soldermask Top")
		(3 "B.Mask" user "Board Geometry/Soldermask Bottom")
		(17 "Dwgs.User" user "User.Drawings")
		(19 "Cmts.User" user "User.Comments")
		(21 "Eco1.User" user "User.Eco1")
		(23 "Eco2.User" user "User.Eco2")
		(25 "Edge.Cuts" user "Board Geometry/Outline")
		(27 "Margin" user)
		(31 "F.CrtYd" user "Package Geometry/Place Bound Top")
		(29 "B.CrtYd" user "Package Geometry/Place Bound Bottom")
		(35 "F.Fab" user "Ref Des/Assembly Top")
		(33 "B.Fab" user "Ref Des/Assembly Bottom")
	)
	(footprint ""
		(layer "B.Cu")
		(at 272.949416 -318.644016)
		(property "Reference" "R30"
			(at 0 0 0)
			(layer "B.SilkS")
			(hide yes)
			(effects
				(font
					(size 1.27 1.27)
				)
				(justify mirror)
			)
		)
		(property "Value" ""
			(at 0 0 0)
			(layer "B.Fab")
			(effects
				(font
					(size 1.27 1.27)
				)
				(justify mirror)
			)
		)
		(duplicate_pad_numbers_are_jumpers no)
		(fp_line
			(start -0.7874 -0.4064)
			(end -0.7874 0.4064)
			(stroke
				(width 0.1524)
				(type default)
			)
			(layer "B.SilkS")
		)
		(fp_line
			(start -0.7874 0.4064)
			(end 0.7874 0.4064)
			(stroke
				(width 0.1524)
				(type default)
			)
			(layer "B.SilkS")
		)
		(fp_line
			(start 0.7874 -0.4064)
			(end -0.7874 -0.4064)
			(stroke
				(width 0.1524)
				(type default)
			)
			(layer "B.SilkS")
		)
		(fp_line
			(start 0.7874 0.4064)
			(end 0.7874 -0.4064)
			(stroke
				(width 0.1524)
				(type default)
			)
			(layer "B.SilkS")
		)
		(fp_line
			(start -0.67945 -0.3048)
			(end -0.67945 0.3048)
			(stroke
				(width 0.1)
				(type default)
			)
			(layer "B.Fab")
		)
		(fp_line
			(start -0.67945 0.3048)
			(end -0.120396 0.3048)
			(stroke
				(width 0.1)
				(type default)
			)
			(layer "B.Fab")
		)
		(fp_line
			(start -0.12065 -0.3048)
			(end -0.67945 -0.3048)
			(stroke
				(width 0.1)
				(type default)
			)
			(layer "B.Fab")
		)
		(fp_line
			(start -0.12065 -0.2794)
			(end -0.12065 -0.3048)
			(stroke
				(width 0.1)
				(type default)
			)
			(layer "B.Fab")
		)
		(fp_line
			(start -0.120396 0.2794)
			(end 0.12065 0.2794)
			(stroke
				(width 0.1)
				(type default)
			)
			(layer "B.Fab")
		)
		(fp_line
			(start -0.120396 0.3048)
			(end -0.120396 0.2794)
			(stroke
				(width 0.1)
				(type default)
			)
			(layer "B.Fab")
		)
		(fp_line
			(start 0.12065 -0.305054)
			(end 0.12065 -0.2794)
			(stroke
				(width 0.1)
				(type default)
			)
			(layer "B.Fab")
		)
		(fp_line
			(start 0.12065 -0.2794)
			(end -0.12065 -0.2794)
			(stroke
				(width 0.1)
				(type default)
			)
			(layer "B.Fab")
		)
		(fp_line
			(start 0.12065 0.2794)
			(end 0.12065 0.3048)
			(stroke
				(width 0.1)
				(type default)
			)
			(layer "B.Fab")
		)
		(fp_line
			(start 0.12065 0.3048)
			(end 0.67945 0.3048)
			(stroke
				(width 0.1)
				(type default)
			)
			(layer "B.Fab")
		)
		(fp_line
			(start 0.67945 -0.305054)
			(end 0.12065 -0.305054)
			(stroke
				(width 0.1)
				(type default)
			)
			(layer "B.Fab")
		)
		(fp_line
			(start 0.67945 0.3048)
			(end 0.67945 -0.305054)
			(stroke
				(width 0.1)
				(type default)
			)
			(layer "B.Fab")
		)
		(pad "1" smd circle
			(at 0.40005 0 180)
			(size 0 0)
			(layers "B.Cu" "B.Mask" "B.Paste")
			(net "PD_CHC_CPU0_DIMM1_SAA")
		)
		(pad "2" smd circle
			(at -0.40005 0 180)
			(size 0 0)
			(layers "B.Cu" "B.Mask" "B.Paste")
			(net "GND")
		)
	)
	(footprint ""
		(layer "B.Cu")
		(at 345.992196 -333.639922 90)
		(property "Reference" "PC303_P0_1"
			(at 0 0 90)
			(layer "B.SilkS")
			(hide yes)
			(effects
				(font
					(size 1.27 1.27)
				)
				(justify mirror)
			)
		)
		(property "Value" ""
			(at 0 0 90)
			(layer "B.Fab")
			(effects
				(font
					(size 1.27 1.27)
				)
				(justify mirror)
			)
		)
		(duplicate_pad_numbers_are_jumpers no)
		(fp_line
			(start 1.524 -0.762)
			(end -1.524 -0.762)
			(stroke
				(width 0.1524)
				(type default)
			)
			(layer "B.SilkS")
		)
		(fp_line
			(start -1.524 -0.762)
			(end -1.524 0.762)
			(stroke
				(width 0.1524)
				(type default)
			)
			(layer "B.SilkS")
		)
		(fp_line
			(start 1.524 0.762)
			(end 1.524 -0.762)
			(stroke
				(width 0.1524)
				(type default)
			)
			(layer "B.SilkS")
		)
		(fp_line
			(start -1.524 0.762)
			(end 1.524 0.762)
			(stroke
				(width 0.1524)
				(type default)
			)
			(layer "B.SilkS")
		)
		(fp_line
			(start 1.1049 -0.724916)
			(end 1.1049 0.724916)
			(stroke
				(width 0.1)
				(type default)
			)
			(layer "B.Fab")
		)
		(fp_line
			(start -1.1049 -0.724916)
			(end 1.1049 -0.724916)
			(stroke
				(width 0.1)
				(type default)
			)
			(layer "B.Fab")
		)
		(fp_line
			(start 1.1049 0.724916)
			(end -1.1049 0.724916)
			(stroke
				(width 0.1)
				(type default)
			)
			(layer "B.Fab")
		)
		(fp_line
			(start -1.1049 0.724916)
			(end -1.1049 -0.724916)
			(stroke
				(width 0.1)
				(type default)
			)
			(layer "B.Fab")
		)
		(pad "1" smd rect
			(at 0.889 0 90)
			(size 1.016 1.27)
			(layers "B.Cu" "B.Mask" "B.Paste")
			(net "SW_P12V_PVCCIN_CPU0_FLT")
		)
		(pad "2" smd rect
			(at -0.889 0 90)
			(size 1.016 1.27)
			(layers "B.Cu" "B.Mask" "B.Paste")
			(net "GND")
		)
	)
	(footprint ""
		(layer "B.Cu")
		(at 77.776578 -343.927938 -90)
		(property "Reference" "PR288"
			(at 0 0 90)
			(layer "B.SilkS")
			(hide yes)
			(effects
				(font
					(size 1.27 1.27)
				)
				(justify mirror)
			)
		)
		(property "Value" ""
			(at 0 0 90)
			(layer "B.Fab")
			(effects
				(font
					(size 1.27 1.27)
				)
				(justify mirror)
			)
		)
		(duplicate_pad_numbers_are_jumpers no)
		(fp_line
			(start -0.7874 0.4064)
			(end 0.7874 0.4064)
			(stroke
				(width 0.1524)
				(type default)
			)
			(layer "B.SilkS")
		)
		(fp_line
			(start 0.7874 0.4064)
			(end 0.7874 -0.4064)
			(stroke
				(width 0.1524)
				(type default)
			)
			(layer "B.SilkS")
		)
		(fp_line
			(start -0.7874 -0.4064)
			(end -0.7874 0.4064)
			(stroke
				(width 0.1524)
				(type default)
			)
			(layer "B.SilkS")
		)
		(fp_line
			(start 0.7874 -0.4064)
			(end -0.7874 -0.4064)
			(stroke
				(width 0.1524)
				(type default)
			)
			(layer "B.SilkS")
		)
		(fp_line
			(start -0.67945 0.3048)
			(end -0.120396 0.3048)
			(stroke
				(width 0.1)
				(type default)
			)
			(layer "B.Fab")
		)
		(fp_line
			(start -0.120396 0.3048)
			(end -0.120396 0.2794)
			(stroke
				(width 0.1)
				(type default)
			)
			(layer "B.Fab")
		)
		(fp_line
			(start 0.12065 0.3048)
			(end 0.67945 0.3048)
			(stroke
				(width 0.1)
				(type default)
			)
			(layer "B.Fab")
		)
		(fp_line
			(start 0.67945 0.3048)
			(end 0.67945 -0.305054)
			(stroke
				(width 0.1)
				(type default)
			)
			(layer "B.Fab")
		)
		(fp_line
			(start -0.120396 0.2794)
			(end 0.12065 0.2794)
			(stroke
				(width 0.1)
				(type default)
			)
			(layer "B.Fab")
		)
		(fp_line
			(start 0.12065 0.2794)
			(end 0.12065 0.3048)
			(stroke
				(width 0.1)
				(type default)
			)
			(layer "B.Fab")
		)
		(fp_line
			(start -0.12065 -0.2794)
			(end -0.12065 -0.3048)
			(stroke
				(width 0.1)
				(type default)
			)
			(layer "B.Fab")
		)
		(fp_line
			(start 0.12065 -0.2794)
			(end -0.12065 -0.2794)
			(stroke
				(width 0.1)
				(type default)
			)
			(layer "B.Fab")
		)
		(fp_line
			(start -0.67945 -0.3048)
			(end -0.67945 0.3048)
			(stroke
				(width 0.1)
				(type default)
			)
			(layer "B.Fab")
		)
		(fp_line
			(start -0.12065 -0.3048)
			(end -0.67945 -0.3048)
			(stroke
				(width 0.1)
				(type default)
			)
			(layer "B.Fab")
		)
		(fp_line
			(start 0.12065 -0.305054)
			(end 0.12065 -0.2794)
			(stroke
				(width 0.1)
				(type default)
			)
			(layer "B.Fab")
		)
		(fp_line
			(start 0.67945 -0.305054)
			(end 0.12065 -0.305054)
			(stroke
				(width 0.1)
				(type default)
			)
			(layer "B.Fab")
		)
		(pad "1" smd circle
			(at 0.40005 0 90)
			(size 0 0)
			(layers "B.Cu" "B.Mask" "B.Paste")
			(net "PVCCIN_CPU1_PVCC")
		)
		(pad "2" smd circle
			(at -0.40005 0 90)
			(size 0 0)
			(layers "B.Cu" "B.Mask" "B.Paste")
			(net "PVCCIN_CPU1_VDD7")
		)
	)
)
